#ISCELL
  mstr_misc dns *
  *
#ISCELL
  pure_quanta quanta_title_block_c *
  *
#ISCELL
  standard offpage *
  page350_i1
#ISCELL
  pure_quanta_power universal_gnd *
  page350_i10
#CELL
  pure_quanta q_res *
  page350_i11
#CELL
  pure_quanta q_res *
  page350_i12
#ISCELL
  pure_quanta_power gnd *
  page350_i13
#CELL
  pure_quanta q_res *
  page350_i14
#ISCELL
  standard offpage *
  page350_i15
#ISCELL
  pure_quanta_power universal_power *
  page350_i16
#CELL
  pure_quanta q_res *
  page350_i17
#CELL
  pure_quanta q_res *
  page350_i18
#ISCELL
  pure_quanta_power universal_power *
  page350_i19
#CELL
  pure_quanta q_res *
  page350_i2
#CELL
  pure_quanta q_res *
  page350_i20
#ISCELL
  pure_quanta_power gnd *
  page350_i21
#CELL
  pure_quanta mosfet_nch_dual *
  page350_i22
#ISCELL
  pure_quanta_power gnd *
  page350_i23
#CELL
  pure_quanta mosfet_nch_dual *
  page350_i24
#CELL
  pure_quanta q_res *
  page350_i25
#ISCELL
  pure_quanta_power universal_power *
  page350_i26
#CELL
  pure_quanta q_res *
  page350_i27
#CELL
  pure_quanta diode_tvs *
  page350_i28
#ISCELL
  pure_quanta_power gnd *
  page350_i29
#CELL
  pure_quanta q_res *
  page350_i3
#ISCELL
  pure_quanta_power universal_power *
  page350_i30
#CELL
  pure_quanta q_cap *
  page350_i31
#ISCELL
  pure_quanta_power gnd *
  page350_i32
#CELL
  pure_quanta q_cap *
  page350_i33
#ISCELL
  pure_quanta_power gnd *
  page350_i34
#CELL
  pure_quanta q_res *
  page350_i35
#ISCELL
  pure_quanta_power gnd *
  page350_i36
#CELL
  pure_quanta q_cap *
  page350_i37
#ISCELL
  pure_quanta_power universal_power *
  page350_i39
#ISCELL
  pure_quanta_power gnd *
  page350_i4
#CELL
  pure_quanta q_res *
  page350_i40
#CELL
  pure_quanta q_res *
  page350_i41
#ISCELL
  pure_quanta_power vccaux15 *
  page350_i42
#CELL
  pure_quanta q_res *
  page350_i43
#ISCELL
  pure_quanta_power gnd *
  page350_i44
#CELL
  pure_quanta q_cap *
  page350_i45
#ISCELL
  pure_quanta_power gnd *
  page350_i46
#ISCELL
  standard offpage *
  page350_i47
#ISCELL
  pure_quanta_power vccaux15 *
  page350_i48
#CELL
  pure_quanta q_res *
  page350_i49
#ISCELL
  pure_quanta_power gnd *
  page350_i5
#CELL
  pure_quanta q_res *
  page350_i50
#CELL
  pure_quanta q_res *
  page350_i51
#CELL
  pure_quanta q_cap *
  page350_i52
#CELL
  pure_quanta q_res *
  page350_i53
#ISCELL
  pure_quanta_power universal_power *
  page350_i54
#ISCELL
  pure_quanta_power gnd *
  page350_i55
#CELL
  pure_quanta q_cap *
  page350_i56
#ISCELL
  pure_quanta_power universal_power *
  page350_i57
#ISCELL
  standard offpage *
  page350_i58
#ISCELL
  pure_quanta_power gnd *
  page350_i59
#CELL
  pure_quanta q_cap *
  page350_i6
#CELL
  pure_quanta q_res *
  page350_i60
#ISCELL
  pure_quanta_power gnd *
  page350_i61
#CELL
  pure_quanta q_res *
  page350_i62
#CELL
  pure_quanta q_res *
  page350_i63
#ISCELL
  pure_quanta_power gnd *
  page350_i64
#CELL
  pure_quanta q_res *
  page350_i65
#CELL
  pure_quanta q_cap *
  page350_i66
#CELL
  pure_quanta q_cap *
  page350_i67
#CELL
  pure_quanta q_res *
  page350_i68
#ISCELL
  pure_quanta_power gnd *
  page350_i69
#ISCELL
  pure_quanta_power gnd *
  page350_i7
#CELL
  pure_quanta q_res *
  page350_i70
#CELL
  pure_quanta q_cap *
  page350_i71
#CELL
  pure_quanta q_cap *
  page350_i72
#CELL
  pure_quanta q_res *
  page350_i73
#CELL
  pure_quanta q_res *
  page350_i74
#ISCELL
  pure_quanta_power gnd *
  page350_i75
#CELL
  pure_quanta q_res *
  page350_i76
#ISCELL
  pure_quanta_power vccaux15 *
  page350_i77
#CELL
  pure_quanta q_res *
  page350_i78
#CELL
  pure_quanta schottky_ac *
  page350_i79
#CELL
  pure_quanta q_cap *
  page350_i8
#CELL
  pure_quanta q_cap *
  page350_i80
#CELL
  pure_quanta q_cap *
  page350_i81
#ISCELL
  standard offpage *
  page350_i82
#ISCELL
  pure_quanta_power gnd *
  page350_i83
#CELL
  pure_quanta q_cap *
  page350_i84
#ISCELL
  pure_quanta_power universal_power *
  page350_i85
#CELL
  pure_quanta max15090bewit *
  page350_i86
#CELL
  pure_quanta q_res *
  page350_i89
#CELL
  pure_quanta mosfet_nch_gds_esd_protected *
  page350_i9
#ISCELL
  standard offpage *
  page350_i90
#CELL
  pure_quanta q_res *
  page350_i91
#ISCELL
  standard offpage *
  page350_i92
#CELL
  pure_quanta q_res *
  page350_i93
#ISCELL
  standard offpage *
  page350_i94
#CELL
  pure_quanta rs31312r *
  page350_i95
